(kicad_pcb
	(version 20260206)
	(generator "pcbnew")
	(generator_version "10.0")
	(general
		(thickness 1.6)
		(legacy_teardrops no)
	)
	(paper "A4")
	(title_block
		(title "04192023_DAF0TMB3IC0_F0TG_MB_C_brd_V02_OCP.brd")
		(comment 1 "Grand Teton / footprints 1443-1449 of 8354")
	)
	(layers
		(0 "F.Cu" signal "TOP")
		(4 "In1.Cu" signal "GND")
		(6 "In2.Cu" signal "IN1")
		(8 "In3.Cu" signal "GND1")
		(10 "In4.Cu" signal "IN2")
		(12 "In5.Cu" signal "GND2")
		(14 "In6.Cu" signal "IN3")
		(16 "In7.Cu" signal "GND3")
		(18 "In8.Cu" signal "VCC")
		(20 "In9.Cu" signal "VCC1")
		(22 "In10.Cu" signal "GND4")
		(24 "In11.Cu" signal "IN4")
		(26 "In12.Cu" signal "GND5")
		(28 "In13.Cu" signal "IN5")
		(30 "In14.Cu" signal "GND6")
		(32 "In15.Cu" signal "IN6")
		(34 "In16.Cu" signal "GND7")
		(2 "B.Cu" signal "BOTTOM")
		(9 "F.Adhes" user "F.Adhesive")
		(11 "B.Adhes" user "B.Adhesive")
		(13 "F.Paste" user "Package Geometry/Pastemask Top")
		(15 "B.Paste" user "Package Geometry/Pastemask Bottom")
		(5 "F.SilkS" user "Ref Des/Silkscreen Top")
		(7 "B.SilkS" user "Ref Des/Silkscreen Bottom")
		(1 "F.Mask" user "Board Geometry/Soldermask Top")
		(3 "B.Mask" user "Board Geometry/Soldermask Bottom")
		(17 "Dwgs.User" user "User.Drawings")
		(19 "Cmts.User" user "User.Comments")
		(21 "Eco1.User" user "User.Eco1")
		(23 "Eco2.User" user "User.Eco2")
		(25 "Edge.Cuts" user "Board Geometry/Outline")
		(27 "Margin" user)
		(31 "F.CrtYd" user "Package Geometry/Place Bound Top")
		(29 "B.CrtYd" user "Package Geometry/Place Bound Bottom")
		(35 "F.Fab" user "Ref Des/Assembly Top")
		(33 "B.Fab" user "Ref Des/Assembly Bottom")
	)
	(footprint ""
		(layer "F.Cu")
		(at 46.16704 -438.753504 90)
		(property "Reference" "R3508"
			(at 0 0 90)
			(layer "F.SilkS")
			(hide yes)
			(effects
				(font
					(size 1.27 1.27)
				)
			)
		)
		(property "Value" ""
			(at 0 0 90)
			(layer "F.Fab")
			(effects
				(font
					(size 1.27 1.27)
				)
			)
		)
		(duplicate_pad_numbers_are_jumpers no)
		(fp_line
			(start 0.7874 -0.4064)
			(end 0.7874 0.4064)
			(stroke
				(width 0.1524)
				(type default)
			)
			(layer "F.SilkS")
		)
		(fp_line
			(start -0.7874 -0.4064)
			(end 0.7874 -0.4064)
			(stroke
				(width 0.1524)
				(type default)
			)
			(layer "F.SilkS")
		)
		(fp_line
			(start 0.7874 0.4064)
			(end -0.7874 0.4064)
			(stroke
				(width 0.1524)
				(type default)
			)
			(layer "F.SilkS")
		)
		(fp_line
			(start -0.7874 0.4064)
			(end -0.7874 -0.4064)
			(stroke
				(width 0.1524)
				(type default)
			)
			(layer "F.SilkS")
		)
		(fp_line
			(start -0.12065 -0.305054)
			(end -0.12065 -0.2794)
			(stroke
				(width 0.1)
				(type default)
			)
			(layer "F.Fab")
		)
		(fp_line
			(start -0.67945 -0.305054)
			(end -0.12065 -0.305054)
			(stroke
				(width 0.1)
				(type default)
			)
			(layer "F.Fab")
		)
		(fp_line
			(start 0.67945 -0.3048)
			(end 0.67945 0.3048)
			(stroke
				(width 0.1)
				(type default)
			)
			(layer "F.Fab")
		)
		(fp_line
			(start 0.12065 -0.3048)
			(end 0.67945 -0.3048)
			(stroke
				(width 0.1)
				(type default)
			)
			(layer "F.Fab")
		)
		(fp_line
			(start 0.12065 -0.2794)
			(end 0.12065 -0.3048)
			(stroke
				(width 0.1)
				(type default)
			)
			(layer "F.Fab")
		)
		(fp_line
			(start -0.12065 -0.2794)
			(end 0.12065 -0.2794)
			(stroke
				(width 0.1)
				(type default)
			)
			(layer "F.Fab")
		)
		(fp_line
			(start 0.120396 0.2794)
			(end -0.12065 0.2794)
			(stroke
				(width 0.1)
				(type default)
			)
			(layer "F.Fab")
		)
		(fp_line
			(start -0.12065 0.2794)
			(end -0.12065 0.3048)
			(stroke
				(width 0.1)
				(type default)
			)
			(layer "F.Fab")
		)
		(fp_line
			(start 0.67945 0.3048)
			(end 0.120396 0.3048)
			(stroke
				(width 0.1)
				(type default)
			)
			(layer "F.Fab")
		)
		(fp_line
			(start 0.120396 0.3048)
			(end 0.120396 0.2794)
			(stroke
				(width 0.1)
				(type default)
			)
			(layer "F.Fab")
		)
		(fp_line
			(start -0.12065 0.3048)
			(end -0.67945 0.3048)
			(stroke
				(width 0.1)
				(type default)
			)
			(layer "F.Fab")
		)
		(fp_line
			(start -0.67945 0.3048)
			(end -0.67945 -0.305054)
			(stroke
				(width 0.1)
				(type default)
			)
			(layer "F.Fab")
		)
		(pad "1" smd circle
			(at -0.40005 0 90)
			(size 0 0)
			(layers "F.Cu" "F.Mask" "F.Paste")
			(net "FM_GPU_PWR_EN_R1")
		)
		(pad "2" smd circle
			(at 0.40005 0 90)
			(size 0 0)
			(layers "F.Cu" "F.Mask" "F.Paste")
			(net "GND")
		)
	)
	(footprint ""
		(layer "F.Cu")
		(at 290.703762 -351.927922)
		(property "Reference" "PR97"
			(at 0 0 0)
			(layer "F.SilkS")
			(hide yes)
			(effects
				(font
					(size 1.27 1.27)
				)
			)
		)
		(property "Value" ""
			(at 0 0 0)
			(layer "F.Fab")
			(effects
				(font
					(size 1.27 1.27)
				)
			)
		)
		(duplicate_pad_numbers_are_jumpers no)
		(fp_line
			(start -0.7874 -0.4064)
			(end 0.7874 -0.4064)
			(stroke
				(width 0.1524)
				(type default)
			)
			(layer "F.SilkS")
		)
		(fp_line
			(start -0.7874 0.4064)
			(end -0.7874 -0.4064)
			(stroke
				(width 0.1524)
				(type default)
			)
			(layer "F.SilkS")
		)
		(fp_line
			(start 0.7874 -0.4064)
			(end 0.7874 0.4064)
			(stroke
				(width 0.1524)
				(type default)
			)
			(layer "F.SilkS")
		)
		(fp_line
			(start 0.7874 0.4064)
			(end -0.7874 0.4064)
			(stroke
				(width 0.1524)
				(type default)
			)
			(layer "F.SilkS")
		)
		(fp_line
			(start -0.67945 -0.305054)
			(end -0.12065 -0.305054)
			(stroke
				(width 0.1)
				(type default)
			)
			(layer "F.Fab")
		)
		(fp_line
			(start -0.67945 0.3048)
			(end -0.67945 -0.305054)
			(stroke
				(width 0.1)
				(type default)
			)
			(layer "F.Fab")
		)
		(fp_line
			(start -0.12065 -0.305054)
			(end -0.12065 -0.2794)
			(stroke
				(width 0.1)
				(type default)
			)
			(layer "F.Fab")
		)
		(fp_line
			(start -0.12065 -0.2794)
			(end 0.12065 -0.2794)
			(stroke
				(width 0.1)
				(type default)
			)
			(layer "F.Fab")
		)
		(fp_line
			(start -0.12065 0.2794)
			(end -0.12065 0.3048)
			(stroke
				(width 0.1)
				(type default)
			)
			(layer "F.Fab")
		)
		(fp_line
			(start -0.12065 0.3048)
			(end -0.67945 0.3048)
			(stroke
				(width 0.1)
				(type default)
			)
			(layer "F.Fab")
		)
		(fp_line
			(start 0.120396 0.2794)
			(end -0.12065 0.2794)
			(stroke
				(width 0.1)
				(type default)
			)
			(layer "F.Fab")
		)
		(fp_line
			(start 0.120396 0.3048)
			(end 0.120396 0.2794)
			(stroke
				(width 0.1)
				(type default)
			)
			(layer "F.Fab")
		)
		(fp_line
			(start 0.12065 -0.3048)
			(end 0.67945 -0.3048)
			(stroke
				(width 0.1)
				(type default)
			)
			(layer "F.Fab")
		)
		(fp_line
			(start 0.12065 -0.2794)
			(end 0.12065 -0.3048)
			(stroke
				(width 0.1)
				(type default)
			)
			(layer "F.Fab")
		)
		(fp_line
			(start 0.67945 -0.3048)
			(end 0.67945 0.3048)
			(stroke
				(width 0.1)
				(type default)
			)
			(layer "F.Fab")
		)
		(fp_line
			(start 0.67945 0.3048)
			(end 0.120396 0.3048)
			(stroke
				(width 0.1)
				(type default)
			)
			(layer "F.Fab")
		)
		(pad "1" smd circle
			(at -0.40005 0)
			(size 0 0)
			(layers "F.Cu" "F.Mask" "F.Paste")
			(net "PVDDIO_P0_LSET2")
		)
		(pad "2" smd circle
			(at 0.40005 0)
			(size 0 0)
			(layers "F.Cu" "F.Mask" "F.Paste")
			(net "GND")
		)
	)
	(footprint ""
		(layer "F.Cu")
		(at 124.088652 -76.251562 90)
		(property "Reference" "PC6017"
			(at 0 0 90)
			(layer "F.SilkS")
			(hide yes)
			(effects
				(font
					(size 1.27 1.27)
				)
			)
		)
		(property "Value" ""
			(at 0 0 90)
			(layer "F.Fab")
			(effects
				(font
					(size 1.27 1.27)
				)
			)
		)
		(duplicate_pad_numbers_are_jumpers no)
		(fp_line
			(start 0.7874 -0.4064)
			(end 0.7874 0.4064)
			(stroke
				(width 0.1524)
				(type default)
			)
			(layer "F.SilkS")
		)
		(fp_line
			(start -0.7874 -0.4064)
			(end 0.7874 -0.4064)
			(stroke
				(width 0.1524)
				(type default)
			)
			(layer "F.SilkS")
		)
		(fp_line
			(start 0.7874 0.4064)
			(end -0.7874 0.4064)
			(stroke
				(width 0.1524)
				(type default)
			)
			(layer "F.SilkS")
		)
		(fp_line
			(start -0.7874 0.4064)
			(end -0.7874 -0.4064)
			(stroke
				(width 0.1524)
				(type default)
			)
			(layer "F.SilkS")
		)
		(fp_line
			(start -0.12065 -0.305054)
			(end -0.12065 -0.2794)
			(stroke
				(width 0.1)
				(type default)
			)
			(layer "F.Fab")
		)
		(fp_line
			(start -0.67945 -0.305054)
			(end -0.12065 -0.305054)
			(stroke
				(width 0.1)
				(type default)
			)
			(layer "F.Fab")
		)
		(fp_line
			(start 0.67945 -0.3048)
			(end 0.67945 0.3048)
			(stroke
				(width 0.1)
				(type default)
			)
			(layer "F.Fab")
		)
		(fp_line
			(start 0.12065 -0.3048)
			(end 0.67945 -0.3048)
			(stroke
				(width 0.1)
				(type default)
			)
			(layer "F.Fab")
		)
		(fp_line
			(start 0.12065 -0.2794)
			(end 0.12065 -0.3048)
			(stroke
				(width 0.1)
				(type default)
			)
			(layer "F.Fab")
		)
		(fp_line
			(start -0.12065 -0.2794)
			(end 0.12065 -0.2794)
			(stroke
				(width 0.1)
				(type default)
			)
			(layer "F.Fab")
		)
		(fp_line
			(start 0.120396 0.2794)
			(end -0.12065 0.2794)
			(stroke
				(width 0.1)
				(type default)
			)
			(layer "F.Fab")
		)
		(fp_line
			(start -0.12065 0.2794)
			(end -0.12065 0.3048)
			(stroke
				(width 0.1)
				(type default)
			)
			(layer "F.Fab")
		)
		(fp_line
			(start 0.67945 0.3048)
			(end 0.120396 0.3048)
			(stroke
				(width 0.1)
				(type default)
			)
			(layer "F.Fab")
		)
		(fp_line
			(start 0.120396 0.3048)
			(end 0.120396 0.2794)
			(stroke
				(width 0.1)
				(type default)
			)
			(layer "F.Fab")
		)
		(fp_line
			(start -0.12065 0.3048)
			(end -0.67945 0.3048)
			(stroke
				(width 0.1)
				(type default)
			)
			(layer "F.Fab")
		)
		(fp_line
			(start -0.67945 0.3048)
			(end -0.67945 -0.305054)
			(stroke
				(width 0.1)
				(type default)
			)
			(layer "F.Fab")
		)
		(pad "1" smd circle
			(at -0.40005 0 90)
			(size 0 0)
			(layers "F.Cu" "F.Mask" "F.Paste")
			(net "SW_P1V2_AUX_BT_R")
		)
		(pad "2" smd circle
			(at 0.40005 0 90)
			(size 0 0)
			(layers "F.Cu" "F.Mask" "F.Paste")
			(net "SW_P1V2_AUX_PH")
		)
	)
	(footprint ""
		(layer "F.Cu")
		(at 413.951928 -351.414842)
		(property "Reference" "H33"
			(at -4.175506 -4.435348 0)
			(unlocked yes)
			(layer "F.SilkS")
			(effects
				(font
					(size 0.7874 0.5842)
					(thickness 0.1524)
				)
				(justify left)
			)
		)
		(property "Value" ""
			(at 0 0 0)
			(layer "F.Fab")
			(effects
				(font
					(size 1.27 1.27)
				)
			)
		)
		(duplicate_pad_numbers_are_jumpers no)
		(pad "1" thru_hole circle
			(at 0 0)
			(size 6.1976 6.1976)
			(drill 3.7338)
			(layers "*.Cu" "*.Mask")
			(remove_unused_layers no)
			(net "GND")
			(clearance -0.9779)
			(padstack
				(mode front_inner_back)
				(layer "Inner"
					(shape circle)
					(size 5.5372 5.5372)
					(clearance -0.6477)
				)
				(layer "B.Cu"
					(shape circle)
					(size 6.1976 6.1976)
					(clearance -0.9779)
				)
			)
		)
	)
	(footprint ""
		(layer "F.Cu")
		(at 114.52987 -68.811394)
		(property "Reference" "C6083"
			(at 0 0 0)
			(layer "F.SilkS")
			(hide yes)
			(effects
				(font
					(size 1.27 1.27)
				)
			)
		)
		(property "Value" ""
			(at 0 0 0)
			(layer "F.Fab")
			(effects
				(font
					(size 1.27 1.27)
				)
			)
		)
		(duplicate_pad_numbers_are_jumpers no)
		(fp_line
			(start -0.7874 -0.4064)
			(end 0.7874 -0.4064)
			(stroke
				(width 0.1524)
				(type default)
			)
			(layer "F.SilkS")
		)
		(fp_line
			(start -0.7874 0.4064)
			(end -0.7874 -0.4064)
			(stroke
				(width 0.1524)
				(type default)
			)
			(layer "F.SilkS")
		)
		(fp_line
			(start 0.7874 -0.4064)
			(end 0.7874 0.4064)
			(stroke
				(width 0.1524)
				(type default)
			)
			(layer "F.SilkS")
		)
		(fp_line
			(start 0.7874 0.4064)
			(end -0.7874 0.4064)
			(stroke
				(width 0.1524)
				(type default)
			)
			(layer "F.SilkS")
		)
		(fp_line
			(start -0.67945 -0.305054)
			(end -0.12065 -0.305054)
			(stroke
				(width 0.1)
				(type default)
			)
			(layer "F.Fab")
		)
		(fp_line
			(start -0.67945 0.3048)
			(end -0.67945 -0.305054)
			(stroke
				(width 0.1)
				(type default)
			)
			(layer "F.Fab")
		)
		(fp_line
			(start -0.12065 -0.305054)
			(end -0.12065 -0.2794)
			(stroke
				(width 0.1)
				(type default)
			)
			(layer "F.Fab")
		)
		(fp_line
			(start -0.12065 -0.2794)
			(end 0.12065 -0.2794)
			(stroke
				(width 0.1)
				(type default)
			)
			(layer "F.Fab")
		)
		(fp_line
			(start -0.12065 0.2794)
			(end -0.12065 0.3048)
			(stroke
				(width 0.1)
				(type default)
			)
			(layer "F.Fab")
		)
		(fp_line
			(start -0.12065 0.3048)
			(end -0.67945 0.3048)
			(stroke
				(width 0.1)
				(type default)
			)
			(layer "F.Fab")
		)
		(fp_line
			(start 0.120396 0.2794)
			(end -0.12065 0.2794)
			(stroke
				(width 0.1)
				(type default)
			)
			(layer "F.Fab")
		)
		(fp_line
			(start 0.120396 0.3048)
			(end 0.120396 0.2794)
			(stroke
				(width 0.1)
				(type default)
			)
			(layer "F.Fab")
		)
		(fp_line
			(start 0.12065 -0.3048)
			(end 0.67945 -0.3048)
			(stroke
				(width 0.1)
				(type default)
			)
			(layer "F.Fab")
		)
		(fp_line
			(start 0.12065 -0.2794)
			(end 0.12065 -0.3048)
			(stroke
				(width 0.1)
				(type default)
			)
			(layer "F.Fab")
		)
		(fp_line
			(start 0.67945 -0.3048)
			(end 0.67945 0.3048)
			(stroke
				(width 0.1)
				(type default)
			)
			(layer "F.Fab")
		)
		(fp_line
			(start 0.67945 0.3048)
			(end 0.120396 0.3048)
			(stroke
				(width 0.1)
				(type default)
			)
			(layer "F.Fab")
		)
		(pad "1" smd circle
			(at -0.40005 0)
			(size 0 0)
			(layers "F.Cu" "F.Mask" "F.Paste")
			(net "P3V3_AUX")
		)
		(pad "2" smd circle
			(at 0.40005 0)
			(size 0 0)
			(layers "F.Cu" "F.Mask" "F.Paste")
			(net "GND")
		)
	)
	(footprint ""
		(layer "F.Cu")
		(at 168.513506 -416.929316 90)
		(property "Reference" "R810"
			(at 0 0 90)
			(layer "F.SilkS")
			(hide yes)
			(effects
				(font
					(size 1.27 1.27)
				)
			)
		)
		(property "Value" ""
			(at 0 0 90)
			(layer "F.Fab")
			(effects
				(font
					(size 1.27 1.27)
				)
			)
		)
		(duplicate_pad_numbers_are_jumpers no)
		(fp_line
			(start 0.32512 -0.175006)
			(end 0.32512 0.175006)
			(stroke
				(width 0.1)
				(type default)
			)
			(layer "F.Fab")
		)
		(fp_line
			(start -0.32512 -0.175006)
			(end 0.32512 -0.175006)
			(stroke
				(width 0.1)
				(type default)
			)
			(layer "F.Fab")
		)
		(fp_line
			(start 0.32512 0.175006)
			(end -0.32512 0.175006)
			(stroke
				(width 0.1)
				(type default)
			)
			(layer "F.Fab")
		)
		(fp_line
			(start -0.32512 0.175006)
			(end -0.32512 -0.175006)
			(stroke
				(width 0.1)
				(type default)
			)
			(layer "F.Fab")
		)
		(pad "1" smd rect
			(at -0.2667 0 90)
			(size 0.3048 0.381)
			(layers "F.Cu" "F.Mask" "F.Paste")
			(net "P1V8_CPU1_RT_1D")
		)
		(pad "2" smd rect
			(at 0.2667 0 270)
			(size 0.3048 0.381)
			(layers "F.Cu" "F.Mask" "F.Paste")
			(net "SMB_RT_CPU1_P3_ROM_R_SDA")
		)
	)
	(footprint ""
		(layer "F.Cu")
		(at 123.35637 -35.430968 180)
		(property "Reference" "C6024"
			(at 0 0 180)
			(layer "F.SilkS")
			(hide yes)
			(effects
				(font
					(size 1.27 1.27)
				)
			)
		)
		(property "Value" ""
			(at 0 0 180)
			(layer "F.Fab")
			(effects
				(font
					(size 1.27 1.27)
				)
			)
		)
		(duplicate_pad_numbers_are_jumpers no)
		(fp_line
			(start 0.7874 0.4064)
			(end -0.7874 0.4064)
			(stroke
				(width 0.1524)
				(type default)
			)
			(layer "F.SilkS")
		)
		(fp_line
			(start 0.7874 -0.4064)
			(end 0.7874 0.4064)
			(stroke
				(width 0.1524)
				(type default)
			)
			(layer "F.SilkS")
		)
		(fp_line
			(start -0.7874 0.4064)
			(end -0.7874 -0.4064)
			(stroke
				(width 0.1524)
				(type default)
			)
			(layer "F.SilkS")
		)
		(fp_line
			(start -0.7874 -0.4064)
			(end 0.7874 -0.4064)
			(stroke
				(width 0.1524)
				(type default)
			)
			(layer "F.SilkS")
		)
		(fp_line
			(start 0.6858 0.3048)
			(end 0.1016 0.3048)
			(stroke
				(width 0.1)
				(type default)
			)
			(layer "F.Fab")
		)
		(fp_line
			(start 0.6858 -0.3048)
			(end 0.6858 0.3048)
			(stroke
				(width 0.1)
				(type default)
			)
			(layer "F.Fab")
		)
		(fp_line
			(start 0.1016 0.3048)
			(end 0.1016 0.2794)
			(stroke
				(width 0.1)
				(type default)
			)
			(layer "F.Fab")
		)
		(fp_line
			(start 0.1016 0.2794)
			(end -0.1016 0.2794)
			(stroke
				(width 0.1)
				(type default)
			)
			(layer "F.Fab")
		)
		(fp_line
			(start 0.1016 -0.2794)
			(end 0.1016 -0.3048)
			(stroke
				(width 0.1)
				(type default)
			)
			(layer "F.Fab")
		)
		(fp_line
			(start 0.1016 -0.3048)
			(end 0.6858 -0.3048)
			(stroke
				(width 0.1)
				(type default)
			)
			(layer "F.Fab")
		)
		(fp_line
			(start -0.1016 0.3048)
			(end -0.6858 0.3048)
			(stroke
				(width 0.1)
				(type default)
			)
			(layer "F.Fab")
		)
		(fp_line
			(start -0.1016 0.2794)
			(end -0.1016 0.3048)
			(stroke
				(width 0.1)
				(type default)
			)
			(layer "F.Fab")
		)
		(fp_line
			(start -0.1016 -0.2794)
			(end 0.1016 -0.2794)
			(stroke
				(width 0.1)
				(type default)
			)
			(layer "F.Fab")
		)
		(fp_line
			(start -0.1016 -0.3048)
			(end -0.1016 -0.2794)
			(stroke
				(width 0.1)
				(type default)
			)
			(layer "F.Fab")
		)
		(fp_line
			(start -0.6858 0.3048)
			(end -0.6858 -0.3048)
			(stroke
				(width 0.1)
				(type default)
			)
			(layer "F.Fab")
		)
		(fp_line
			(start -0.6858 -0.3048)
			(end -0.1016 -0.3048)
			(stroke
				(width 0.1)
				(type default)
			)
			(layer "F.Fab")
		)
		(pad "1" smd rect
			(at -0.40005 0)
			(size 0.4572 0.508)
			(layers "F.Cu" "F.Mask" "F.Paste")
			(net "USB3_CPU0_BMC_HUB1_TX_DN")
		)
		(pad "2" smd rect
			(at 0.40005 0)
			(size 0.4572 0.508)
			(layers "F.Cu" "F.Mask" "F.Paste")
			(net "USB3_CPU0_BMC_TX_BUF_C_DN")
		)
	)
)
